FILE_TYPE=LIBRARY_PARTS;
primitive 'TUSB8042AIRGCR';
  pin
    'USB_SSRXM_UP':
      PIN_NUMBER='(59,0)';
      INPUT_LOAD='(-0.01,0.01)';
    'USB_SSRXM_DN2':
      PIN_NUMBER='(15,0)';
      INPUT_LOAD='(-0.01,0.01)';
    'USB_SSRXP_DN2':
      PIN_NUMBER='(14,0)';
      INPUT_LOAD='(-0.01,0.01)';
    'USB_SSTXP_DN2':
      PIN_NUMBER='(11,0)';
      OUTPUT_LOAD='(1.0,-1.0)';
    'USB_SSTXM_DN2':
      PIN_NUMBER='(12,0)';
      OUTPUT_LOAD='(1.0,-1.0)';
    'USB_DM_DN3':
      PIN_NUMBER='(18,0)';
      BIDIRECTIONAL='TRUE';
      INPUT_LOAD='(-0.01,0.01)';
      OUTPUT_LOAD='(1.0,-1.0)';
    'USB_SSTXM_DN3':
      PIN_NUMBER='(20,0)';
      OUTPUT_LOAD='(1.0,-1.0)';
    'USB_SSTXP_UP':
      PIN_NUMBER='(55,0)';
      OUTPUT_LOAD='(1.0,-1.0)';
    'USB_DM_UP':
      PIN_NUMBER='(54,0)';
      BIDIRECTIONAL='TRUE';
      INPUT_LOAD='(-0.01,0.01)';
      OUTPUT_LOAD='(1.0,-1.0)';
    'USB_SSRXM_DN3':
      PIN_NUMBER='(23,0)';
      INPUT_LOAD='(-0.01,0.01)';
    'USB_DP_DN4':
      PIN_NUMBER='(24,0)';
      BIDIRECTIONAL='TRUE';
      INPUT_LOAD='(-0.01,0.01)';
      OUTPUT_LOAD='(1.0,-1.0)';
    'USB_DP_DN3':
      PIN_NUMBER='(17,0)';
      BIDIRECTIONAL='TRUE';
      INPUT_LOAD='(-0.01,0.01)';
      OUTPUT_LOAD='(1.0,-1.0)';
    'USB_SSRXP_UP':
      PIN_NUMBER='(58,0)';
      INPUT_LOAD='(-0.01,0.01)';
    'USB_DP_DN2':
      PIN_NUMBER='(9,0)';
      BIDIRECTIONAL='TRUE';
      INPUT_LOAD='(-0.01,0.01)';
      OUTPUT_LOAD='(1.0,-1.0)';
    'USB_SSRXP_DN1':
      PIN_NUMBER='(6,0)';
      INPUT_LOAD='(-0.01,0.01)';
    'USB_SSTXP_DN4':
      PIN_NUMBER='(26,0)';
      OUTPUT_LOAD='(1.0,-1.0)';
    'USB_DM_DN1':
      PIN_NUMBER='(2,0)';
      BIDIRECTIONAL='TRUE';
      INPUT_LOAD='(-0.01,0.01)';
      OUTPUT_LOAD='(1.0,-1.0)';
    'USB_DM_DN4':
      PIN_NUMBER='(25,0)';
      BIDIRECTIONAL='TRUE';
      INPUT_LOAD='(-0.01,0.01)';
      OUTPUT_LOAD='(1.0,-1.0)';
    'USB_SSRXP_DN4':
      PIN_NUMBER='(29,0)';
      INPUT_LOAD='(-0.01,0.01)';
    'USB_SSRXM_DN4':
      PIN_NUMBER='(30,0)';
      INPUT_LOAD='(-0.01,0.01)';
    'USB_SSRXP_DN3':
      PIN_NUMBER='(22,0)';
      INPUT_LOAD='(-0.01,0.01)';
    'TH_VSS':
      PIN_NUMBER='(TH,0)';
      PINUSE='POWER';
      NO_LOAD_CHECK='Both';
      NO_IO_CHECK='Both';
      NO_ASSERT_CHECK='TRUE';
      NO_DIR_CHECK='TRUE';
      ALLOW_CONNECT='TRUE';
    'USB_DP_UP':
      PIN_NUMBER='(53,0)';
      BIDIRECTIONAL='TRUE';
      INPUT_LOAD='(-0.01,0.01)';
      OUTPUT_LOAD='(1.0,-1.0)';
    'USB_SSTXM_UP':
      PIN_NUMBER='(56,0)';
      OUTPUT_LOAD='(1.0,-1.0)';
    'USB_DP_DN1':
      PIN_NUMBER='(1,0)';
      BIDIRECTIONAL='TRUE';
      INPUT_LOAD='(-0.01,0.01)';
      OUTPUT_LOAD='(1.0,-1.0)';
    'USB_SSRXM_DN1':
      PIN_NUMBER='(7,0)';
      INPUT_LOAD='(-0.01,0.01)';
    'USB_SSTXP_DN1':
      PIN_NUMBER='(3,0)';
      OUTPUT_LOAD='(1.0,-1.0)';
    'USB_SSTXM_DN1':
      PIN_NUMBER='(4,0)';
      OUTPUT_LOAD='(1.0,-1.0)';
    'USB_DM_DN2':
      PIN_NUMBER='(10,0)';
      BIDIRECTIONAL='TRUE';
      INPUT_LOAD='(-0.01,0.01)';
      OUTPUT_LOAD='(1.0,-1.0)';
    'USB_SSTXP_DN3':
      PIN_NUMBER='(19,0)';
      OUTPUT_LOAD='(1.0,-1.0)';
    'USB_SSTXM_DN4':
      PIN_NUMBER='(27,0)';
      OUTPUT_LOAD='(1.0,-1.0)';
    'USB_VBUS':
      PIN_NUMBER='(48,0)';
      INPUT_LOAD='(-0.01,0.01)';
    'PWRCTL1||BATEN1':
      PIN_NUMBER='(36,0)';
      BIDIRECTIONAL='TRUE';
      INPUT_LOAD='(-0.01,0.01)';
      OUTPUT_LOAD='(1.0,-1.0)';
    'PWRCTL2||BATEN2':
      PIN_NUMBER='(35,0)';
      BIDIRECTIONAL='TRUE';
      INPUT_LOAD='(-0.01,0.01)';
      OUTPUT_LOAD='(1.0,-1.0)';
    'PWRCTL3||BATEN3':
      PIN_NUMBER='(33,0)';
      BIDIRECTIONAL='TRUE';
      INPUT_LOAD='(-0.01,0.01)';
      OUTPUT_LOAD='(1.0,-1.0)';
    'PWRCTL4||BATEN4':
      PIN_NUMBER='(32,0)';
      BIDIRECTIONAL='TRUE';
      INPUT_LOAD='(-0.01,0.01)';
      OUTPUT_LOAD='(1.0,-1.0)';
    'PWRCTL_POL':
      PIN_NUMBER='(41,0)';
      BIDIRECTIONAL='TRUE';
      INPUT_LOAD='(-0.01,0.01)';
      OUTPUT_LOAD='(1.0,-1.0)';
    'GRSTZ':
      PIN_NUMBER='(50,0)';
      INPUT_LOAD='(-0.01,0.01)';
    'OVERCUR1Z':
      PIN_NUMBER='(46,0)';
      INPUT_LOAD='(-0.01,0.01)';
    'OVERCUR2Z':
      PIN_NUMBER='(47,0)';
      INPUT_LOAD='(-0.01,0.01)';
    'OVERCUR3Z':
      PIN_NUMBER='(44,0)';
      INPUT_LOAD='(-0.01,0.01)';
    'OVERCUR4Z':
      PIN_NUMBER='(43,0)';
      INPUT_LOAD='(-0.01,0.01)';
    'TEST':
      PIN_NUMBER='(49,0)';
      INPUT_LOAD='(-0.01,0.01)';
    'USB_R1':
      PIN_NUMBER='(64,0)';
      INPUT_LOAD='(-0.01,0.01)';
    'NC_1':
      PIN_NUMBER='(60,0)';
      OUTPUT_TYPE='(TS,TS)';
      INPUT_LOAD='(-0.01,0.01)';
      OUTPUT_LOAD='(1.0,-1.0)';
    'VDD_13':
      PIN_NUMBER='(0,13)';
      PINUSE='POWER';
      NO_LOAD_CHECK='Both';
      NO_IO_CHECK='Both';
      NO_ASSERT_CHECK='TRUE';
      NO_DIR_CHECK='TRUE';
      ALLOW_CONNECT='TRUE';
    'SDA||SMBDAT':
      PIN_NUMBER='(0,37)';
      BIDIRECTIONAL='TRUE';
      INPUT_LOAD='(-0.01,0.01)';
      OUTPUT_LOAD='(1.0,-1.0)';
    'VDD_28':
      PIN_NUMBER='(0,28)';
      PINUSE='POWER';
      NO_LOAD_CHECK='Both';
      NO_IO_CHECK='Both';
      NO_ASSERT_CHECK='TRUE';
      NO_DIR_CHECK='TRUE';
      ALLOW_CONNECT='TRUE';
    'VDD33_16':
      PIN_NUMBER='(0,16)';
      PINUSE='POWER';
      NO_LOAD_CHECK='Both';
      NO_IO_CHECK='Both';
      NO_ASSERT_CHECK='TRUE';
      NO_DIR_CHECK='TRUE';
      ALLOW_CONNECT='TRUE';
    'VDD33_34':
      PIN_NUMBER='(0,34)';
      PINUSE='POWER';
      NO_LOAD_CHECK='Both';
      NO_IO_CHECK='Both';
      NO_ASSERT_CHECK='TRUE';
      NO_DIR_CHECK='TRUE';
      ALLOW_CONNECT='TRUE';
    'VDD33_52':
      PIN_NUMBER='(0,52)';
      PINUSE='POWER';
      NO_LOAD_CHECK='Both';
      NO_IO_CHECK='Both';
      NO_ASSERT_CHECK='TRUE';
      NO_DIR_CHECK='TRUE';
      ALLOW_CONNECT='TRUE';
    'FULLPWRMGMTZ||FULLAUTOZ||SMBA1||SS_UP':
      PIN_NUMBER='(0,40)';
      BIDIRECTIONAL='TRUE';
      INPUT_LOAD='(-0.01,0.01)';
      OUTPUT_LOAD='(1.0,-1.0)';
    'GANGED||SMBA2||HS_UP':
      PIN_NUMBER='(0,42)';
      BIDIRECTIONAL='TRUE';
      INPUT_LOAD='(-0.01,0.01)';
      OUTPUT_LOAD='(1.0,-1.0)';
    'SCL||SMBCLK':
      PIN_NUMBER='(0,38)';
      BIDIRECTIONAL='TRUE';
      INPUT_LOAD='(-0.01,0.01)';
      OUTPUT_LOAD='(1.0,-1.0)';
    'SMBUSZ||SS_SUSPEND':
      PIN_NUMBER='(0,39)';
      BIDIRECTIONAL='TRUE';
      INPUT_LOAD='(-0.01,0.01)';
      OUTPUT_LOAD='(1.0,-1.0)';
    'VDD33_63':
      PIN_NUMBER='(0,63)';
      PINUSE='POWER';
      NO_LOAD_CHECK='Both';
      NO_IO_CHECK='Both';
      NO_ASSERT_CHECK='TRUE';
      NO_DIR_CHECK='TRUE';
      ALLOW_CONNECT='TRUE';
    'VDD_51':
      PIN_NUMBER='(0,51)';
      PINUSE='POWER';
      NO_LOAD_CHECK='Both';
      NO_IO_CHECK='Both';
      NO_ASSERT_CHECK='TRUE';
      NO_DIR_CHECK='TRUE';
      ALLOW_CONNECT='TRUE';
    'AUTOENZ||HS_SUSPEND':
      PIN_NUMBER='(0,45)';
      BIDIRECTIONAL='TRUE';
      INPUT_LOAD='(-0.01,0.01)';
      OUTPUT_LOAD='(1.0,-1.0)';
    'VDD_8':
      PIN_NUMBER='(0,8)';
      PINUSE='POWER';
      NO_LOAD_CHECK='Both';
      NO_IO_CHECK='Both';
      NO_ASSERT_CHECK='TRUE';
      NO_DIR_CHECK='TRUE';
      ALLOW_CONNECT='TRUE';
    'VDD_5':
      PIN_NUMBER='(0,5)';
      PINUSE='POWER';
      NO_LOAD_CHECK='Both';
      NO_IO_CHECK='Both';
      NO_ASSERT_CHECK='TRUE';
      NO_DIR_CHECK='TRUE';
      ALLOW_CONNECT='TRUE';
    'VDD_57':
      PIN_NUMBER='(0,57)';
      PINUSE='POWER';
      NO_LOAD_CHECK='Both';
      NO_IO_CHECK='Both';
      NO_ASSERT_CHECK='TRUE';
      NO_DIR_CHECK='TRUE';
      ALLOW_CONNECT='TRUE';
    'VDD_21':
      PIN_NUMBER='(0,21)';
      PINUSE='POWER';
      NO_LOAD_CHECK='Both';
      NO_IO_CHECK='Both';
      NO_ASSERT_CHECK='TRUE';
      NO_DIR_CHECK='TRUE';
      ALLOW_CONNECT='TRUE';
    'VDD_31':
      PIN_NUMBER='(0,31)';
      PINUSE='POWER';
      NO_LOAD_CHECK='Both';
      NO_IO_CHECK='Both';
      NO_ASSERT_CHECK='TRUE';
      NO_DIR_CHECK='TRUE';
      ALLOW_CONNECT='TRUE';
    'XO':
      PIN_NUMBER='(0,61)';
      OUTPUT_LOAD='(1.0,-1.0)';
    'XI':
      PIN_NUMBER='(0,62)';
      INPUT_LOAD='(-0.01,0.01)';
  end_pin;
  body
    PART_NAME='TUSB8042AIRGCR';
    BODY_NAME='TUSB8042AIRGCR';
    PHYS_DES_PREFIX='U';
    CLASS='IC';
  end_body;
end_primitive;

END.
